# T6G (Grand Teton) — schematic netlist excerpt (pin names and nets, part order shuffled) for the footprints in the layout excerpt that follows; sources: Cadence DE-HDL packaged netlist, KiCad conversion of 04192023_DAF0TMB3IC0_F0TG_MB_C_brd_V02_OCP.brd

C2327  Q_CAP  22UF 4V 20% X6S  pkg C0402  page 73 : A = PVDDCR_CPU0_P1 ; B = GND
C2131  Q_CAP  22UF 4V 20% X6S  pkg C0402  page 68 : A = PVDDIO_P0 ; B = GND
PC571_5  Q_CAP  22UF 16V 20% X6S  pkg C0805  page 196 : A = SW_P12V_AUX_PVDDCR_CPU0_P0_FLT ; B = GND

(kicad_pcb
	(version 20260206)
	(generator "pcbnew")
	(generator_version "10.0")
	(general
		(thickness 1.6)
		(legacy_teardrops no)
	)
	(paper "A4")
	(title_block
		(title "04192023_DAF0TMB3IC0_F0TG_MB_C_brd_V02_OCP.brd")
		(comment 1 "Grand Teton / footprints 5917-5919 of 8354")
	)
	(layers
		(0 "F.Cu" signal "TOP")
		(4 "In1.Cu" signal "GND")
		(6 "In2.Cu" signal "IN1")
		(8 "In3.Cu" signal "GND1")
		(10 "In4.Cu" signal "IN2")
		(12 "In5.Cu" signal "GND2")
		(14 "In6.Cu" signal "IN3")
		(16 "In7.Cu" signal "GND3")
		(18 "In8.Cu" signal "VCC")
		(20 "In9.Cu" signal "VCC1")
		(22 "In10.Cu" signal "GND4")
		(24 "In11.Cu" signal "IN4")
		(26 "In12.Cu" signal "GND5")
		(28 "In13.Cu" signal "IN5")
		(30 "In14.Cu" signal "GND6")
		(32 "In15.Cu" signal "IN6")
		(34 "In16.Cu" signal "GND7")
		(2 "B.Cu" signal "BOTTOM")
		(9 "F.Adhes" user "F.Adhesive")
		(11 "B.Adhes" user "B.Adhesive")
		(13 "F.Paste" user "Package Geometry/Pastemask Top")
		(15 "B.Paste" user "Package Geometry/Pastemask Bottom")
		(5 "F.SilkS" user "Ref Des/Silkscreen Top")
		(7 "B.SilkS" user "Ref Des/Silkscreen Bottom")
		(1 "F.Mask" user "Board Geometry/Soldermask Top")
		(3 "B.Mask" user "Board Geometry/Soldermask Bottom")
		(17 "Dwgs.User" user "User.Drawings")
		(19 "Cmts.User" user "User.Comments")
		(21 "Eco1.User" user "User.Eco1")
		(23 "Eco2.User" user "User.Eco2")
		(25 "Edge.Cuts" user "Board Geometry/Outline")
		(27 "Margin" user)
		(31 "F.CrtYd" user "Package Geometry/Place Bound Top")
		(29 "B.CrtYd" user "Package Geometry/Place Bound Bottom")
		(35 "F.Fab" user "Ref Des/Assembly Top")
		(33 "B.Fab" user "Ref Des/Assembly Bottom")
	)
	(footprint ""
		(layer "B.Cu")
		(at 356.29596 -259.845048 180)
		(property "Reference" "C2131"
			(at 0 0 0)
			(layer "B.SilkS")
			(hide yes)
			(effects
				(font
					(size 1.27 1.27)
				)
				(justify mirror)
			)
		)
		(property "Value" ""
			(at 0 0 0)
			(layer "B.Fab")
			(effects
				(font
					(size 1.27 1.27)
				)
				(justify mirror)
			)
		)
		(duplicate_pad_numbers_are_jumpers no)
		(fp_line
			(start 0.7874 0.4064)
			(end 0.7874 -0.4064)
			(stroke
				(width 0.1524)
				(type default)
			)
			(layer "B.SilkS")
		)
		(fp_line
			(start 0.7874 -0.4064)
			(end -0.7874 -0.4064)
			(stroke
				(width 0.1524)
				(type default)
			)
			(layer "B.SilkS")
		)
		(fp_line
			(start -0.7874 0.4064)
			(end 0.7874 0.4064)
			(stroke
				(width 0.1524)
				(type default)
			)
			(layer "B.SilkS")
		)
		(fp_line
			(start -0.7874 -0.4064)
			(end -0.7874 0.4064)
			(stroke
				(width 0.1524)
				(type default)
			)
			(layer "B.SilkS")
		)
		(fp_line
			(start 0.67945 0.3048)
			(end 0.67945 -0.305054)
			(stroke
				(width 0.1)
				(type default)
			)
			(layer "B.Fab")
		)
		(fp_line
			(start 0.67945 -0.305054)
			(end 0.12065 -0.305054)
			(stroke
				(width 0.1)
				(type default)
			)
			(layer "B.Fab")
		)
		(fp_line
			(start 0.12065 0.3048)
			(end 0.67945 0.3048)
			(stroke
				(width 0.1)
				(type default)
			)
			(layer "B.Fab")
		)
		(fp_line
			(start 0.12065 0.2794)
			(end 0.12065 0.3048)
			(stroke
				(width 0.1)
				(type default)
			)
			(layer "B.Fab")
		)
		(fp_line
			(start 0.12065 -0.2794)
			(end -0.12065 -0.2794)
			(stroke
				(width 0.1)
				(type default)
			)
			(layer "B.Fab")
		)
		(fp_line
			(start 0.12065 -0.305054)
			(end 0.12065 -0.2794)
			(stroke
				(width 0.1)
				(type default)
			)
			(layer "B.Fab")
		)
		(fp_line
			(start -0.120396 0.3048)
			(end -0.120396 0.2794)
			(stroke
				(width 0.1)
				(type default)
			)
			(layer "B.Fab")
		)
		(fp_line
			(start -0.120396 0.2794)
			(end 0.12065 0.2794)
			(stroke
				(width 0.1)
				(type default)
			)
			(layer "B.Fab")
		)
		(fp_line
			(start -0.12065 -0.2794)
			(end -0.12065 -0.3048)
			(stroke
				(width 0.1)
				(type default)
			)
			(layer "B.Fab")
		)
		(fp_line
			(start -0.12065 -0.3048)
			(end -0.67945 -0.3048)
			(stroke
				(width 0.1)
				(type default)
			)
			(layer "B.Fab")
		)
		(fp_line
			(start -0.67945 0.3048)
			(end -0.120396 0.3048)
			(stroke
				(width 0.1)
				(type default)
			)
			(layer "B.Fab")
		)
		(fp_line
			(start -0.67945 -0.3048)
			(end -0.67945 0.3048)
			(stroke
				(width 0.1)
				(type default)
			)
			(layer "B.Fab")
		)
		(pad "1" smd circle
			(at 0.40005 0)
			(size 0 0)
			(layers "B.Cu" "B.Mask" "B.Paste")
			(net "PVDDIO_P0")
		)
		(pad "2" smd circle
			(at -0.40005 0)
			(size 0 0)
			(layers "B.Cu" "B.Mask" "B.Paste")
			(net "GND")
		)
	)
	(footprint ""
		(layer "B.Cu")
		(at 354.818696 -165.72992 90)
		(property "Reference" "PC571_5"
			(at 0 0 90)
			(layer "B.SilkS")
			(hide yes)
			(effects
				(font
					(size 1.27 1.27)
				)
				(justify mirror)
			)
		)
		(property "Value" ""
			(at 0 0 90)
			(layer "B.Fab")
			(effects
				(font
					(size 1.27 1.27)
				)
				(justify mirror)
			)
		)
		(duplicate_pad_numbers_are_jumpers no)
		(fp_line
			(start 1.524 -0.762)
			(end -1.524 -0.762)
			(stroke
				(width 0.1524)
				(type default)
			)
			(layer "B.SilkS")
		)
		(fp_line
			(start -1.524 -0.762)
			(end -1.524 0.762)
			(stroke
				(width 0.1524)
				(type default)
			)
			(layer "B.SilkS")
		)
		(fp_line
			(start 1.524 0.762)
			(end 1.524 -0.762)
			(stroke
				(width 0.1524)
				(type default)
			)
			(layer "B.SilkS")
		)
		(fp_line
			(start -1.524 0.762)
			(end 1.524 0.762)
			(stroke
				(width 0.1524)
				(type default)
			)
			(layer "B.SilkS")
		)
		(fp_line
			(start 1.1049 -0.724916)
			(end 1.1049 0.724916)
			(stroke
				(width 0.1)
				(type default)
			)
			(layer "B.Fab")
		)
		(fp_line
			(start -1.1049 -0.724916)
			(end 1.1049 -0.724916)
			(stroke
				(width 0.1)
				(type default)
			)
			(layer "B.Fab")
		)
		(fp_line
			(start 1.1049 0.724916)
			(end -1.1049 0.724916)
			(stroke
				(width 0.1)
				(type default)
			)
			(layer "B.Fab")
		)
		(fp_line
			(start -1.1049 0.724916)
			(end -1.1049 -0.724916)
			(stroke
				(width 0.1)
				(type default)
			)
			(layer "B.Fab")
		)
		(pad "1" smd rect
			(at 0.889 0 90)
			(size 1.016 1.27)
			(layers "B.Cu" "B.Mask" "B.Paste")
			(net "SW_P12V_AUX_PVDDCR_CPU0_P0_FLT")
		)
		(pad "2" smd rect
			(at -0.889 0 90)
			(size 1.016 1.27)
			(layers "B.Cu" "B.Mask" "B.Paste")
			(net "GND")
		)
	)
	(footprint ""
		(layer "B.Cu")
		(at 106.48823 -250.891294 180)
		(property "Reference" "C2327"
			(at 0 0 0)
			(layer "B.SilkS")
			(hide yes)
			(effects
				(font
					(size 1.27 1.27)
				)
				(justify mirror)
			)
		)
		(property "Value" ""
			(at 0 0 0)
			(layer "B.Fab")
			(effects
				(font
					(size 1.27 1.27)
				)
				(justify mirror)
			)
		)
		(duplicate_pad_numbers_are_jumpers no)
		(fp_line
			(start 0.7874 0.4064)
			(end 0.7874 -0.4064)
			(stroke
				(width 0.1524)
				(type default)
			)
			(layer "B.SilkS")
		)
		(fp_line
			(start 0.7874 -0.4064)
			(end -0.7874 -0.4064)
			(stroke
				(width 0.1524)
				(type default)
			)
			(layer "B.SilkS")
		)
		(fp_line
			(start -0.7874 0.4064)
			(end 0.7874 0.4064)
			(stroke
				(width 0.1524)
				(type default)
			)
			(layer "B.SilkS")
		)
		(fp_line
			(start -0.7874 -0.4064)
			(end -0.7874 0.4064)
			(stroke
				(width 0.1524)
				(type default)
			)
			(layer "B.SilkS")
		)
		(fp_line
			(start 0.67945 0.3048)
			(end 0.67945 -0.305054)
			(stroke
				(width 0.1)
				(type default)
			)
			(layer "B.Fab")
		)
		(fp_line
			(start 0.67945 -0.305054)
			(end 0.12065 -0.305054)
			(stroke
				(width 0.1)
				(type default)
			)
			(layer "B.Fab")
		)
		(fp_line
			(start 0.12065 0.3048)
			(end 0.67945 0.3048)
			(stroke
				(width 0.1)
				(type default)
			)
			(layer "B.Fab")
		)
		(fp_line
			(start 0.12065 0.2794)
			(end 0.12065 0.3048)
			(stroke
				(width 0.1)
				(type default)
			)
			(layer "B.Fab")
		)
		(fp_line
			(start 0.12065 -0.2794)
			(end -0.12065 -0.2794)
			(stroke
				(width 0.1)
				(type default)
			)
			(layer "B.Fab")
		)
		(fp_line
			(start 0.12065 -0.305054)
			(end 0.12065 -0.2794)
			(stroke
				(width 0.1)
				(type default)
			)
			(layer "B.Fab")
		)
		(fp_line
			(start -0.120396 0.3048)
			(end -0.120396 0.2794)
			(stroke
				(width 0.1)
				(type default)
			)
			(layer "B.Fab")
		)
		(fp_line
			(start -0.120396 0.2794)
			(end 0.12065 0.2794)
			(stroke
				(width 0.1)
				(type default)
			)
			(layer "B.Fab")
		)
		(fp_line
			(start -0.12065 -0.2794)
			(end -0.12065 -0.3048)
			(stroke
				(width 0.1)
				(type default)
			)
			(layer "B.Fab")
		)
		(fp_line
			(start -0.12065 -0.3048)
			(end -0.67945 -0.3048)
			(stroke
				(width 0.1)
				(type default)
			)
			(layer "B.Fab")
		)
		(fp_line
			(start -0.67945 0.3048)
			(end -0.120396 0.3048)
			(stroke
				(width 0.1)
				(type default)
			)
			(layer "B.Fab")
		)
		(fp_line
			(start -0.67945 -0.3048)
			(end -0.67945 0.3048)
			(stroke
				(width 0.1)
				(type default)
			)
			(layer "B.Fab")
		)
		(pad "1" smd circle
			(at 0.40005 0)
			(size 0 0)
			(layers "B.Cu" "B.Mask" "B.Paste")
			(net "PVDDCR_CPU0_P1")
		)
		(pad "2" smd circle
			(at -0.40005 0)
			(size 0 0)
			(layers "B.Cu" "B.Mask" "B.Paste")
			(net "GND")
		)
	)
)
